(kicad_pcb
	(version 20260206)
	(generator "pcbnew")
	(generator_version "10.0")
	(general
		(thickness 1.6)
		(legacy_teardrops no)
	)
	(paper "A4")
	(title_block
		(title "01162023_DA0F0TEBIF0_F0T_Expander_BD_F_brd_V02_OCP.brd")
		(comment 1 "Grand Teton / footprints 7377-7384 of 9728")
	)
	(layers
		(0 "F.Cu" signal "TOP")
		(4 "In1.Cu" signal "GND")
		(6 "In2.Cu" signal "VCC")
		(8 "In3.Cu" signal "VCC1")
		(10 "In4.Cu" signal "GND1")
		(12 "In5.Cu" signal "IN1")
		(14 "In6.Cu" signal "GND2")
		(16 "In7.Cu" signal "IN2")
		(18 "In8.Cu" signal "GND3")
		(20 "In9.Cu" signal "IN3")
		(22 "In10.Cu" signal "GND4")
		(24 "In11.Cu" signal "IN4")
		(26 "In12.Cu" signal "GND5")
		(28 "In13.Cu" signal "IN5")
		(30 "In14.Cu" signal "GND6")
		(32 "In15.Cu" signal "IN6")
		(34 "In16.Cu" signal "GND7")
		(2 "B.Cu" signal "BOTTOM")
		(9 "F.Adhes" user "F.Adhesive")
		(11 "B.Adhes" user "B.Adhesive")
		(13 "F.Paste" user "Package Geometry/Pastemask Top")
		(15 "B.Paste" user "Package Geometry/Pastemask Bottom")
		(5 "F.SilkS" user "Ref Des/Silkscreen Top")
		(7 "B.SilkS" user "Ref Des/Silkscreen Bottom")
		(1 "F.Mask" user "Board Geometry/Soldermask Top")
		(3 "B.Mask" user "Board Geometry/Soldermask Bottom")
		(17 "Dwgs.User" user "User.Drawings")
		(19 "Cmts.User" user "User.Comments")
		(21 "Eco1.User" user "User.Eco1")
		(23 "Eco2.User" user "User.Eco2")
		(25 "Edge.Cuts" user "Board Geometry/Outline")
		(27 "Margin" user)
		(31 "F.CrtYd" user "Package Geometry/Place Bound Top")
		(29 "B.CrtYd" user "Package Geometry/Place Bound Bottom")
		(35 "F.Fab" user "Ref Des/Assembly Top")
		(33 "B.Fab" user "Ref Des/Assembly Bottom")
	)
	(footprint ""
		(layer "B.Cu")
		(at 207.500728 -233.686604)
		(property "Reference" "R6326"
			(at 0 0 0)
			(layer "B.SilkS")
			(hide yes)
			(effects
				(font
					(size 1.27 1.27)
				)
				(justify mirror)
			)
		)
		(property "Value" ""
			(at 0 0 0)
			(layer "B.Fab")
			(effects
				(font
					(size 1.27 1.27)
				)
				(justify mirror)
			)
		)
		(duplicate_pad_numbers_are_jumpers no)
		(fp_line
			(start -0.7874 -0.4064)
			(end -0.7874 0.4064)
			(stroke
				(width 0.1524)
				(type default)
			)
			(layer "B.SilkS")
		)
		(fp_line
			(start -0.7874 0.4064)
			(end 0.7874 0.4064)
			(stroke
				(width 0.1524)
				(type default)
			)
			(layer "B.SilkS")
		)
		(fp_line
			(start 0.7874 -0.4064)
			(end -0.7874 -0.4064)
			(stroke
				(width 0.1524)
				(type default)
			)
			(layer "B.SilkS")
		)
		(fp_line
			(start 0.7874 0.4064)
			(end 0.7874 -0.4064)
			(stroke
				(width 0.1524)
				(type default)
			)
			(layer "B.SilkS")
		)
		(fp_line
			(start -0.67945 -0.3048)
			(end -0.67945 0.3048)
			(stroke
				(width 0.1)
				(type default)
			)
			(layer "B.Fab")
		)
		(fp_line
			(start -0.67945 0.3048)
			(end -0.120396 0.3048)
			(stroke
				(width 0.1)
				(type default)
			)
			(layer "B.Fab")
		)
		(fp_line
			(start -0.12065 -0.3048)
			(end -0.67945 -0.3048)
			(stroke
				(width 0.1)
				(type default)
			)
			(layer "B.Fab")
		)
		(fp_line
			(start -0.12065 -0.2794)
			(end -0.12065 -0.3048)
			(stroke
				(width 0.1)
				(type default)
			)
			(layer "B.Fab")
		)
		(fp_line
			(start -0.120396 0.2794)
			(end 0.12065 0.2794)
			(stroke
				(width 0.1)
				(type default)
			)
			(layer "B.Fab")
		)
		(fp_line
			(start -0.120396 0.3048)
			(end -0.120396 0.2794)
			(stroke
				(width 0.1)
				(type default)
			)
			(layer "B.Fab")
		)
		(fp_line
			(start 0.12065 -0.305054)
			(end 0.12065 -0.2794)
			(stroke
				(width 0.1)
				(type default)
			)
			(layer "B.Fab")
		)
		(fp_line
			(start 0.12065 -0.2794)
			(end -0.12065 -0.2794)
			(stroke
				(width 0.1)
				(type default)
			)
			(layer "B.Fab")
		)
		(fp_line
			(start 0.12065 0.2794)
			(end 0.12065 0.3048)
			(stroke
				(width 0.1)
				(type default)
			)
			(layer "B.Fab")
		)
		(fp_line
			(start 0.12065 0.3048)
			(end 0.67945 0.3048)
			(stroke
				(width 0.1)
				(type default)
			)
			(layer "B.Fab")
		)
		(fp_line
			(start 0.67945 -0.305054)
			(end 0.12065 -0.305054)
			(stroke
				(width 0.1)
				(type default)
			)
			(layer "B.Fab")
		)
		(fp_line
			(start 0.67945 0.3048)
			(end 0.67945 -0.305054)
			(stroke
				(width 0.1)
				(type default)
			)
			(layer "B.Fab")
		)
		(pad "1" smd circle
			(at 0.40005 0 180)
			(size 0 0)
			(layers "B.Cu" "B.Mask" "B.Paste")
			(net "SMB_PEX1_SCL")
		)
		(pad "2" smd circle
			(at -0.40005 0 180)
			(size 0 0)
			(layers "B.Cu" "B.Mask" "B.Paste")
			(net "SMB_PEX1_MUX_SCL")
		)
	)
	(footprint ""
		(layer "B.Cu")
		(at 187.390532 -118.711218 180)
		(property "Reference" "R177"
			(at 0 0 0)
			(layer "B.SilkS")
			(hide yes)
			(effects
				(font
					(size 1.27 1.27)
				)
				(justify mirror)
			)
		)
		(property "Value" ""
			(at 0 0 0)
			(layer "B.Fab")
			(effects
				(font
					(size 1.27 1.27)
				)
				(justify mirror)
			)
		)
		(duplicate_pad_numbers_are_jumpers no)
		(fp_line
			(start 0.7874 0.4064)
			(end 0.7874 -0.4064)
			(stroke
				(width 0.1524)
				(type default)
			)
			(layer "B.SilkS")
		)
		(fp_line
			(start 0.7874 -0.4064)
			(end -0.7874 -0.4064)
			(stroke
				(width 0.1524)
				(type default)
			)
			(layer "B.SilkS")
		)
		(fp_line
			(start -0.7874 0.4064)
			(end 0.7874 0.4064)
			(stroke
				(width 0.1524)
				(type default)
			)
			(layer "B.SilkS")
		)
		(fp_line
			(start -0.7874 -0.4064)
			(end -0.7874 0.4064)
			(stroke
				(width 0.1524)
				(type default)
			)
			(layer "B.SilkS")
		)
		(fp_line
			(start 0.67945 0.3048)
			(end 0.67945 -0.305054)
			(stroke
				(width 0.1)
				(type default)
			)
			(layer "B.Fab")
		)
		(fp_line
			(start 0.67945 -0.305054)
			(end 0.12065 -0.305054)
			(stroke
				(width 0.1)
				(type default)
			)
			(layer "B.Fab")
		)
		(fp_line
			(start 0.12065 0.3048)
			(end 0.67945 0.3048)
			(stroke
				(width 0.1)
				(type default)
			)
			(layer "B.Fab")
		)
		(fp_line
			(start 0.12065 0.2794)
			(end 0.12065 0.3048)
			(stroke
				(width 0.1)
				(type default)
			)
			(layer "B.Fab")
		)
		(fp_line
			(start 0.12065 -0.2794)
			(end -0.12065 -0.2794)
			(stroke
				(width 0.1)
				(type default)
			)
			(layer "B.Fab")
		)
		(fp_line
			(start 0.12065 -0.305054)
			(end 0.12065 -0.2794)
			(stroke
				(width 0.1)
				(type default)
			)
			(layer "B.Fab")
		)
		(fp_line
			(start -0.120396 0.3048)
			(end -0.120396 0.2794)
			(stroke
				(width 0.1)
				(type default)
			)
			(layer "B.Fab")
		)
		(fp_line
			(start -0.120396 0.2794)
			(end 0.12065 0.2794)
			(stroke
				(width 0.1)
				(type default)
			)
			(layer "B.Fab")
		)
		(fp_line
			(start -0.12065 -0.2794)
			(end -0.12065 -0.3048)
			(stroke
				(width 0.1)
				(type default)
			)
			(layer "B.Fab")
		)
		(fp_line
			(start -0.12065 -0.3048)
			(end -0.67945 -0.3048)
			(stroke
				(width 0.1)
				(type default)
			)
			(layer "B.Fab")
		)
		(fp_line
			(start -0.67945 0.3048)
			(end -0.120396 0.3048)
			(stroke
				(width 0.1)
				(type default)
			)
			(layer "B.Fab")
		)
		(fp_line
			(start -0.67945 -0.3048)
			(end -0.67945 0.3048)
			(stroke
				(width 0.1)
				(type default)
			)
			(layer "B.Fab")
		)
		(pad "1" smd circle
			(at 0.40005 0)
			(size 0 0)
			(layers "B.Cu" "B.Mask" "B.Paste")
			(net "NIC3_AUX_PWR_EN")
		)
		(pad "2" smd circle
			(at -0.40005 0)
			(size 0 0)
			(layers "B.Cu" "B.Mask" "B.Paste")
			(net "GND")
		)
	)
	(footprint ""
		(layer "B.Cu")
		(at 47.7774 -299.5422 90)
		(property "Reference" "C3023"
			(at 0 0 90)
			(layer "B.SilkS")
			(hide yes)
			(effects
				(font
					(size 1.27 1.27)
				)
				(justify mirror)
			)
		)
		(property "Value" ""
			(at 0 0 90)
			(layer "B.Fab")
			(effects
				(font
					(size 1.27 1.27)
				)
				(justify mirror)
			)
		)
		(duplicate_pad_numbers_are_jumpers no)
		(fp_line
			(start 0.299974 -0.150114)
			(end -0.299974 -0.150114)
			(stroke
				(width 0.1)
				(type default)
			)
			(layer "B.Fab")
		)
		(fp_line
			(start -0.299974 -0.150114)
			(end -0.299974 0.150114)
			(stroke
				(width 0.1)
				(type default)
			)
			(layer "B.Fab")
		)
		(fp_line
			(start 0.299974 0.150114)
			(end 0.299974 -0.150114)
			(stroke
				(width 0.1)
				(type default)
			)
			(layer "B.Fab")
		)
		(fp_line
			(start -0.299974 0.150114)
			(end 0.299974 0.150114)
			(stroke
				(width 0.1)
				(type default)
			)
			(layer "B.Fab")
		)
		(pad "1" smd rect
			(at 0.2667 0 270)
			(size 0.3048 0.381)
			(layers "B.Cu" "B.Mask" "B.Paste")
			(net "PCEPLL0_VDDA18_PEX0")
		)
		(pad "2" smd rect
			(at -0.2667 0 270)
			(size 0.3048 0.381)
			(layers "B.Cu" "B.Mask" "B.Paste")
			(net "GND")
		)
	)
	(footprint ""
		(layer "B.Cu")
		(at 235.569252 -217.104214 -90)
		(property "Reference" "C2024"
			(at 0 0 90)
			(layer "B.SilkS")
			(hide yes)
			(effects
				(font
					(size 1.27 1.27)
				)
				(justify mirror)
			)
		)
		(property "Value" ""
			(at 0 0 90)
			(layer "B.Fab")
			(effects
				(font
					(size 1.27 1.27)
				)
				(justify mirror)
			)
		)
		(duplicate_pad_numbers_are_jumpers no)
		(fp_line
			(start -0.69215 0.2921)
			(end 0.69215 0.2921)
			(stroke
				(width 0.1524)
				(type default)
			)
			(layer "B.SilkS")
		)
		(fp_line
			(start 0.69215 0.2921)
			(end 0.69215 -0.2921)
			(stroke
				(width 0.1524)
				(type default)
			)
			(layer "B.SilkS")
		)
		(fp_line
			(start -0.69215 -0.2921)
			(end -0.69215 0.2921)
			(stroke
				(width 0.1524)
				(type default)
			)
			(layer "B.SilkS")
		)
		(fp_line
			(start 0.69215 -0.2921)
			(end -0.69215 -0.2921)
			(stroke
				(width 0.1524)
				(type default)
			)
			(layer "B.SilkS")
		)
		(fp_line
			(start -0.51435 0.2794)
			(end 0.51435 0.2794)
			(stroke
				(width 0.1)
				(type default)
			)
			(layer "B.Fab")
		)
		(fp_line
			(start 0.51435 0.2794)
			(end 0.51435 -0.2794)
			(stroke
				(width 0.1)
				(type default)
			)
			(layer "B.Fab")
		)
		(fp_line
			(start -0.51435 -0.2794)
			(end -0.51435 0.2794)
			(stroke
				(width 0.1)
				(type default)
			)
			(layer "B.Fab")
		)
		(fp_line
			(start 0.51435 -0.2794)
			(end -0.51435 -0.2794)
			(stroke
				(width 0.1)
				(type default)
			)
			(layer "B.Fab")
		)
		(pad "1" smd circle
			(at 0.40005 0 90)
			(size 0 0)
			(layers "B.Cu" "B.Mask" "B.Paste")
			(net "P1V2_BIC_PLL")
		)
		(pad "2" smd circle
			(at -0.40005 0 90)
			(size 0 0)
			(layers "B.Cu" "B.Mask" "B.Paste")
			(net "GND")
		)
		(zone
			(layer "B.Cu")
			(hatch none 0.5)
			(connect_pads
				(clearance 0)
			)
			(min_thickness 0.25)
			(keepout
				(tracks not_allowed)
				(vias allowed)
				(pads allowed)
				(copperpour not_allowed)
				(footprints allowed)
			)
			(placement
				(enabled no)
				(sheetname "")
			)
			(fill
				(thermal_gap 0.5)
				(thermal_bridge_width 0.5)
				(island_removal_mode 0)
			)
			(polygon
				(pts
					(xy 235.481622 -216.913714) (xy 235.423456 -217.005154) (xy 235.423456 -217.204544) (xy 235.481622 -217.294714)
					(xy 235.656882 -217.294714) (xy 235.715302 -217.204544) (xy 235.715302 -217.005154) (xy 235.657136 -216.913714)
				)
			)
		)
	)
	(footprint ""
		(layer "B.Cu")
		(at 363.093 -228.981)
		(property "Reference" "R3504"
			(at 0 0 0)
			(layer "B.SilkS")
			(hide yes)
			(effects
				(font
					(size 1.27 1.27)
				)
				(justify mirror)
			)
		)
		(property "Value" ""
			(at 0 0 0)
			(layer "B.Fab")
			(effects
				(font
					(size 1.27 1.27)
				)
				(justify mirror)
			)
		)
		(duplicate_pad_numbers_are_jumpers no)
		(fp_line
			(start -0.7874 -0.4064)
			(end -0.7874 0.4064)
			(stroke
				(width 0.1524)
				(type default)
			)
			(layer "B.SilkS")
		)
		(fp_line
			(start -0.7874 0.4064)
			(end 0.7874 0.4064)
			(stroke
				(width 0.1524)
				(type default)
			)
			(layer "B.SilkS")
		)
		(fp_line
			(start 0.7874 -0.4064)
			(end -0.7874 -0.4064)
			(stroke
				(width 0.1524)
				(type default)
			)
			(layer "B.SilkS")
		)
		(fp_line
			(start 0.7874 0.4064)
			(end 0.7874 -0.4064)
			(stroke
				(width 0.1524)
				(type default)
			)
			(layer "B.SilkS")
		)
		(fp_line
			(start -0.67945 -0.3048)
			(end -0.67945 0.3048)
			(stroke
				(width 0.1)
				(type default)
			)
			(layer "B.Fab")
		)
		(fp_line
			(start -0.67945 0.3048)
			(end -0.120396 0.3048)
			(stroke
				(width 0.1)
				(type default)
			)
			(layer "B.Fab")
		)
		(fp_line
			(start -0.12065 -0.3048)
			(end -0.67945 -0.3048)
			(stroke
				(width 0.1)
				(type default)
			)
			(layer "B.Fab")
		)
		(fp_line
			(start -0.12065 -0.2794)
			(end -0.12065 -0.3048)
			(stroke
				(width 0.1)
				(type default)
			)
			(layer "B.Fab")
		)
		(fp_line
			(start -0.120396 0.2794)
			(end 0.12065 0.2794)
			(stroke
				(width 0.1)
				(type default)
			)
			(layer "B.Fab")
		)
		(fp_line
			(start -0.120396 0.3048)
			(end -0.120396 0.2794)
			(stroke
				(width 0.1)
				(type default)
			)
			(layer "B.Fab")
		)
		(fp_line
			(start 0.12065 -0.305054)
			(end 0.12065 -0.2794)
			(stroke
				(width 0.1)
				(type default)
			)
			(layer "B.Fab")
		)
		(fp_line
			(start 0.12065 -0.2794)
			(end -0.12065 -0.2794)
			(stroke
				(width 0.1)
				(type default)
			)
			(layer "B.Fab")
		)
		(fp_line
			(start 0.12065 0.2794)
			(end 0.12065 0.3048)
			(stroke
				(width 0.1)
				(type default)
			)
			(layer "B.Fab")
		)
		(fp_line
			(start 0.12065 0.3048)
			(end 0.67945 0.3048)
			(stroke
				(width 0.1)
				(type default)
			)
			(layer "B.Fab")
		)
		(fp_line
			(start 0.67945 -0.305054)
			(end 0.12065 -0.305054)
			(stroke
				(width 0.1)
				(type default)
			)
			(layer "B.Fab")
		)
		(fp_line
			(start 0.67945 0.3048)
			(end 0.67945 -0.305054)
			(stroke
				(width 0.1)
				(type default)
			)
			(layer "B.Fab")
		)
		(pad "1" smd circle
			(at 0.40005 0 180)
			(size 0 0)
			(layers "B.Cu" "B.Mask" "B.Paste")
			(net "P1V8_PEX")
		)
		(pad "2" smd circle
			(at -0.40005 0 180)
			(size 0 0)
			(layers "B.Cu" "B.Mask" "B.Paste")
			(net "SPI_PEX3_SDIO2_R1")
		)
	)
	(footprint ""
		(layer "B.Cu")
		(at 295.649904 -303.499774 -90)
		(property "Reference" "C3257"
			(at 0 0 90)
			(layer "B.SilkS")
			(hide yes)
			(effects
				(font
					(size 1.27 1.27)
				)
				(justify mirror)
			)
		)
		(property "Value" ""
			(at 0 0 90)
			(layer "B.Fab")
			(effects
				(font
					(size 1.27 1.27)
				)
				(justify mirror)
			)
		)
		(duplicate_pad_numbers_are_jumpers no)
		(fp_line
			(start -0.299974 0.150114)
			(end 0.299974 0.150114)
			(stroke
				(width 0.1)
				(type default)
			)
			(layer "B.Fab")
		)
		(fp_line
			(start 0.299974 0.150114)
			(end 0.299974 -0.150114)
			(stroke
				(width 0.1)
				(type default)
			)
			(layer "B.Fab")
		)
		(fp_line
			(start -0.299974 -0.150114)
			(end -0.299974 0.150114)
			(stroke
				(width 0.1)
				(type default)
			)
			(layer "B.Fab")
		)
		(fp_line
			(start 0.299974 -0.150114)
			(end -0.299974 -0.150114)
			(stroke
				(width 0.1)
				(type default)
			)
			(layer "B.Fab")
		)
		(pad "1" smd rect
			(at 0.2667 0 90)
			(size 0.3048 0.381)
			(layers "B.Cu" "B.Mask" "B.Paste")
			(net "P1V25_PEX2")
		)
		(pad "2" smd rect
			(at -0.2667 0 90)
			(size 0.3048 0.381)
			(layers "B.Cu" "B.Mask" "B.Paste")
			(net "GND")
		)
	)
	(footprint ""
		(layer "B.Cu")
		(at 289.04565 -296.37482)
		(property "Reference" "C1627"
			(at 0 0 0)
			(layer "B.SilkS")
			(hide yes)
			(effects
				(font
					(size 1.27 1.27)
				)
				(justify mirror)
			)
		)
		(property "Value" ""
			(at 0 0 0)
			(layer "B.Fab")
			(effects
				(font
					(size 1.27 1.27)
				)
				(justify mirror)
			)
		)
		(duplicate_pad_numbers_are_jumpers no)
		(fp_line
			(start -0.299974 -0.150114)
			(end -0.299974 0.150114)
			(stroke
				(width 0.1)
				(type default)
			)
			(layer "B.Fab")
		)
		(fp_line
			(start -0.299974 0.150114)
			(end 0.299974 0.150114)
			(stroke
				(width 0.1)
				(type default)
			)
			(layer "B.Fab")
		)
		(fp_line
			(start 0.299974 -0.150114)
			(end -0.299974 -0.150114)
			(stroke
				(width 0.1)
				(type default)
			)
			(layer "B.Fab")
		)
		(fp_line
			(start 0.299974 0.150114)
			(end 0.299974 -0.150114)
			(stroke
				(width 0.1)
				(type default)
			)
			(layer "B.Fab")
		)
		(pad "1" smd rect
			(at 0.2667 0 180)
			(size 0.3048 0.381)
			(layers "B.Cu" "B.Mask" "B.Paste")
			(net "P0V8_PEX2")
		)
		(pad "2" smd rect
			(at -0.2667 0 180)
			(size 0.3048 0.381)
			(layers "B.Cu" "B.Mask" "B.Paste")
			(net "GND")
		)
	)
	(footprint ""
		(layer "B.Cu")
		(at 130.49885 -171.43857 90)
		(property "Reference" "R1467"
			(at 0 0 90)
			(layer "B.SilkS")
			(hide yes)
			(effects
				(font
					(size 1.27 1.27)
				)
				(justify mirror)
			)
		)
		(property "Value" ""
			(at 0 0 90)
			(layer "B.Fab")
			(effects
				(font
					(size 1.27 1.27)
				)
				(justify mirror)
			)
		)
		(duplicate_pad_numbers_are_jumpers no)
		(fp_line
			(start 0.7874 -0.4064)
			(end -0.7874 -0.4064)
			(stroke
				(width 0.1524)
				(type default)
			)
			(layer "B.SilkS")
		)
		(fp_line
			(start -0.7874 -0.4064)
			(end -0.7874 0.4064)
			(stroke
				(width 0.1524)
				(type default)
			)
			(layer "B.SilkS")
		)
		(fp_line
			(start 0.7874 0.4064)
			(end 0.7874 -0.4064)
			(stroke
				(width 0.1524)
				(type default)
			)
			(layer "B.SilkS")
		)
		(fp_line
			(start -0.7874 0.4064)
			(end 0.7874 0.4064)
			(stroke
				(width 0.1524)
				(type default)
			)
			(layer "B.SilkS")
		)
		(fp_line
			(start 0.67945 -0.305054)
			(end 0.12065 -0.305054)
			(stroke
				(width 0.1)
				(type default)
			)
			(layer "B.Fab")
		)
		(fp_line
			(start 0.12065 -0.305054)
			(end 0.12065 -0.2794)
			(stroke
				(width 0.1)
				(type default)
			)
			(layer "B.Fab")
		)
		(fp_line
			(start -0.12065 -0.3048)
			(end -0.67945 -0.3048)
			(stroke
				(width 0.1)
				(type default)
			)
			(layer "B.Fab")
		)
		(fp_line
			(start -0.67945 -0.3048)
			(end -0.67945 0.3048)
			(stroke
				(width 0.1)
				(type default)
			)
			(layer "B.Fab")
		)
		(fp_line
			(start 0.12065 -0.2794)
			(end -0.12065 -0.2794)
			(stroke
				(width 0.1)
				(type default)
			)
			(layer "B.Fab")
		)
		(fp_line
			(start -0.12065 -0.2794)
			(end -0.12065 -0.3048)
			(stroke
				(width 0.1)
				(type default)
			)
			(layer "B.Fab")
		)
		(fp_line
			(start 0.12065 0.2794)
			(end 0.12065 0.3048)
			(stroke
				(width 0.1)
				(type default)
			)
			(layer "B.Fab")
		)
		(fp_line
			(start -0.120396 0.2794)
			(end 0.12065 0.2794)
			(stroke
				(width 0.1)
				(type default)
			)
			(layer "B.Fab")
		)
		(fp_line
			(start 0.67945 0.3048)
			(end 0.67945 -0.305054)
			(stroke
				(width 0.1)
				(type default)
			)
			(layer "B.Fab")
		)
		(fp_line
			(start 0.12065 0.3048)
			(end 0.67945 0.3048)
			(stroke
				(width 0.1)
				(type default)
			)
			(layer "B.Fab")
		)
		(fp_line
			(start -0.120396 0.3048)
			(end -0.120396 0.2794)
			(stroke
				(width 0.1)
				(type default)
			)
			(layer "B.Fab")
		)
		(fp_line
			(start -0.67945 0.3048)
			(end -0.120396 0.3048)
			(stroke
				(width 0.1)
				(type default)
			)
			(layer "B.Fab")
		)
		(pad "1" smd circle
			(at 0.40005 0 270)
			(size 0 0)
			(layers "B.Cu" "B.Mask" "B.Paste")
			(net "SMB_BMC_9QXL2001_SDA")
		)
		(pad "2" smd circle
			(at -0.40005 0 270)
			(size 0 0)
			(layers "B.Cu" "B.Mask" "B.Paste")
			(net "SMB_CLK_ISO_R_SDA")
		)
	)
)
